# T6G (Grand Teton) — schematic netlist excerpt (pin names and nets, part order shuffled) for the footprints in the layout excerpt that follows; sources: Cadence DE-HDL packaged netlist, KiCad conversion of 04192023_DAF0TMB3IC0_F0TG_MB_C_brd_V02_OCP.brd

R770  Q_RES  15.4K 1% CHIP  pkg 0402LF  page 99 : A = PD_CHB_CPU1_DIMM_SAA ; B = GND
C1023  Q_CAP  10UF 6.3V 20% X6S  pkg C0402  page 312 : A = P0V9_CPU0_RT3_2A ; B = GND

(kicad_pcb
	(version 20260206)
	(generator "pcbnew")
	(generator_version "10.0")
	(general
		(thickness 1.6)
		(legacy_teardrops no)
	)
	(paper "A4")
	(title_block
		(title "04192023_DAF0TMB3IC0_F0TG_MB_C_brd_V02_OCP.brd")
		(comment 1 "Grand Teton / footprints 5758-5759 of 8354")
	)
	(layers
		(0 "F.Cu" signal "TOP")
		(4 "In1.Cu" signal "GND")
		(6 "In2.Cu" signal "IN1")
		(8 "In3.Cu" signal "GND1")
		(10 "In4.Cu" signal "IN2")
		(12 "In5.Cu" signal "GND2")
		(14 "In6.Cu" signal "IN3")
		(16 "In7.Cu" signal "GND3")
		(18 "In8.Cu" signal "VCC")
		(20 "In9.Cu" signal "VCC1")
		(22 "In10.Cu" signal "GND4")
		(24 "In11.Cu" signal "IN4")
		(26 "In12.Cu" signal "GND5")
		(28 "In13.Cu" signal "IN5")
		(30 "In14.Cu" signal "GND6")
		(32 "In15.Cu" signal "IN6")
		(34 "In16.Cu" signal "GND7")
		(2 "B.Cu" signal "BOTTOM")
		(9 "F.Adhes" user "F.Adhesive")
		(11 "B.Adhes" user "B.Adhesive")
		(13 "F.Paste" user "Package Geometry/Pastemask Top")
		(15 "B.Paste" user "Package Geometry/Pastemask Bottom")
		(5 "F.SilkS" user "Ref Des/Silkscreen Top")
		(7 "B.SilkS" user "Ref Des/Silkscreen Bottom")
		(1 "F.Mask" user "Board Geometry/Soldermask Top")
		(3 "B.Mask" user "Board Geometry/Soldermask Bottom")
		(17 "Dwgs.User" user "User.Drawings")
		(19 "Cmts.User" user "User.Comments")
		(21 "Eco1.User" user "User.Eco1")
		(23 "Eco2.User" user "User.Eco2")
		(25 "Edge.Cuts" user "Board Geometry/Outline")
		(27 "Margin" user)
		(31 "F.CrtYd" user "Package Geometry/Place Bound Top")
		(29 "B.CrtYd" user "Package Geometry/Place Bound Bottom")
		(35 "F.Fab" user "Ref Des/Assembly Top")
		(33 "B.Fab" user "Ref Des/Assembly Bottom")
	)
	(footprint ""
		(layer "B.Cu")
		(at 48.555148 -194.885564 180)
		(property "Reference" "R770"
			(at 0 0 0)
			(layer "B.SilkS")
			(hide yes)
			(effects
				(font
					(size 1.27 1.27)
				)
				(justify mirror)
			)
		)
		(property "Value" ""
			(at 0 0 0)
			(layer "B.Fab")
			(effects
				(font
					(size 1.27 1.27)
				)
				(justify mirror)
			)
		)
		(duplicate_pad_numbers_are_jumpers no)
		(fp_line
			(start 0.7874 0.4064)
			(end 0.7874 -0.4064)
			(stroke
				(width 0.1524)
				(type default)
			)
			(layer "B.SilkS")
		)
		(fp_line
			(start 0.7874 -0.4064)
			(end -0.7874 -0.4064)
			(stroke
				(width 0.1524)
				(type default)
			)
			(layer "B.SilkS")
		)
		(fp_line
			(start -0.7874 0.4064)
			(end 0.7874 0.4064)
			(stroke
				(width 0.1524)
				(type default)
			)
			(layer "B.SilkS")
		)
		(fp_line
			(start -0.7874 -0.4064)
			(end -0.7874 0.4064)
			(stroke
				(width 0.1524)
				(type default)
			)
			(layer "B.SilkS")
		)
		(fp_line
			(start 0.67945 0.3048)
			(end 0.67945 -0.305054)
			(stroke
				(width 0.1)
				(type default)
			)
			(layer "B.Fab")
		)
		(fp_line
			(start 0.67945 -0.305054)
			(end 0.12065 -0.305054)
			(stroke
				(width 0.1)
				(type default)
			)
			(layer "B.Fab")
		)
		(fp_line
			(start 0.12065 0.3048)
			(end 0.67945 0.3048)
			(stroke
				(width 0.1)
				(type default)
			)
			(layer "B.Fab")
		)
		(fp_line
			(start 0.12065 0.2794)
			(end 0.12065 0.3048)
			(stroke
				(width 0.1)
				(type default)
			)
			(layer "B.Fab")
		)
		(fp_line
			(start 0.12065 -0.2794)
			(end -0.12065 -0.2794)
			(stroke
				(width 0.1)
				(type default)
			)
			(layer "B.Fab")
		)
		(fp_line
			(start 0.12065 -0.305054)
			(end 0.12065 -0.2794)
			(stroke
				(width 0.1)
				(type default)
			)
			(layer "B.Fab")
		)
		(fp_line
			(start -0.120396 0.3048)
			(end -0.120396 0.2794)
			(stroke
				(width 0.1)
				(type default)
			)
			(layer "B.Fab")
		)
		(fp_line
			(start -0.120396 0.2794)
			(end 0.12065 0.2794)
			(stroke
				(width 0.1)
				(type default)
			)
			(layer "B.Fab")
		)
		(fp_line
			(start -0.12065 -0.2794)
			(end -0.12065 -0.3048)
			(stroke
				(width 0.1)
				(type default)
			)
			(layer "B.Fab")
		)
		(fp_line
			(start -0.12065 -0.3048)
			(end -0.67945 -0.3048)
			(stroke
				(width 0.1)
				(type default)
			)
			(layer "B.Fab")
		)
		(fp_line
			(start -0.67945 0.3048)
			(end -0.120396 0.3048)
			(stroke
				(width 0.1)
				(type default)
			)
			(layer "B.Fab")
		)
		(fp_line
			(start -0.67945 -0.3048)
			(end -0.67945 0.3048)
			(stroke
				(width 0.1)
				(type default)
			)
			(layer "B.Fab")
		)
		(pad "1" smd circle
			(at 0.40005 0)
			(size 0 0)
			(layers "B.Cu" "B.Mask" "B.Paste")
			(net "PD_CHB_CPU1_DIMM_SAA")
		)
		(pad "2" smd circle
			(at -0.40005 0)
			(size 0 0)
			(layers "B.Cu" "B.Mask" "B.Paste")
			(net "GND")
		)
	)
	(footprint ""
		(layer "B.Cu")
		(at 384.89128 -398.942052 90)
		(property "Reference" "C1023"
			(at 0 0 90)
			(layer "B.SilkS")
			(hide yes)
			(effects
				(font
					(size 1.27 1.27)
				)
				(justify mirror)
			)
		)
		(property "Value" ""
			(at 0 0 90)
			(layer "B.Fab")
			(effects
				(font
					(size 1.27 1.27)
				)
				(justify mirror)
			)
		)
		(duplicate_pad_numbers_are_jumpers no)
		(fp_line
			(start 0.7874 -0.4064)
			(end -0.7874 -0.4064)
			(stroke
				(width 0.1524)
				(type default)
			)
			(layer "B.SilkS")
		)
		(fp_line
			(start -0.7874 -0.4064)
			(end -0.7874 0.4064)
			(stroke
				(width 0.1524)
				(type default)
			)
			(layer "B.SilkS")
		)
		(fp_line
			(start 0.7874 0.4064)
			(end 0.7874 -0.4064)
			(stroke
				(width 0.1524)
				(type default)
			)
			(layer "B.SilkS")
		)
		(fp_line
			(start -0.7874 0.4064)
			(end 0.7874 0.4064)
			(stroke
				(width 0.1524)
				(type default)
			)
			(layer "B.SilkS")
		)
		(fp_line
			(start 0.67945 -0.305054)
			(end 0.12065 -0.305054)
			(stroke
				(width 0.1)
				(type default)
			)
			(layer "B.Fab")
		)
		(fp_line
			(start 0.12065 -0.305054)
			(end 0.12065 -0.2794)
			(stroke
				(width 0.1)
				(type default)
			)
			(layer "B.Fab")
		)
		(fp_line
			(start -0.12065 -0.3048)
			(end -0.67945 -0.3048)
			(stroke
				(width 0.1)
				(type default)
			)
			(layer "B.Fab")
		)
		(fp_line
			(start -0.67945 -0.3048)
			(end -0.67945 0.3048)
			(stroke
				(width 0.1)
				(type default)
			)
			(layer "B.Fab")
		)
		(fp_line
			(start 0.12065 -0.2794)
			(end -0.12065 -0.2794)
			(stroke
				(width 0.1)
				(type default)
			)
			(layer "B.Fab")
		)
		(fp_line
			(start -0.12065 -0.2794)
			(end -0.12065 -0.3048)
			(stroke
				(width 0.1)
				(type default)
			)
			(layer "B.Fab")
		)
		(fp_line
			(start 0.12065 0.2794)
			(end 0.12065 0.3048)
			(stroke
				(width 0.1)
				(type default)
			)
			(layer "B.Fab")
		)
		(fp_line
			(start -0.120396 0.2794)
			(end 0.12065 0.2794)
			(stroke
				(width 0.1)
				(type default)
			)
			(layer "B.Fab")
		)
		(fp_line
			(start 0.67945 0.3048)
			(end 0.67945 -0.305054)
			(stroke
				(width 0.1)
				(type default)
			)
			(layer "B.Fab")
		)
		(fp_line
			(start 0.12065 0.3048)
			(end 0.67945 0.3048)
			(stroke
				(width 0.1)
				(type default)
			)
			(layer "B.Fab")
		)
		(fp_line
			(start -0.120396 0.3048)
			(end -0.120396 0.2794)
			(stroke
				(width 0.1)
				(type default)
			)
			(layer "B.Fab")
		)
		(fp_line
			(start -0.67945 0.3048)
			(end -0.120396 0.3048)
			(stroke
				(width 0.1)
				(type default)
			)
			(layer "B.Fab")
		)
		(pad "1" smd circle
			(at 0.40005 0 270)
			(size 0 0)
			(layers "B.Cu" "B.Mask" "B.Paste")
			(net "P0V9_CPU0_RT3_2A")
		)
		(pad "2" smd circle
			(at -0.40005 0 270)
			(size 0 0)
			(layers "B.Cu" "B.Mask" "B.Paste")
			(net "GND")
		)
	)
)
